# T6G (Grand Teton) — schematic netlist excerpt (pin names and nets, part order shuffled) for the footprints in the layout excerpt that follows; sources: Cadence DE-HDL packaged netlist, KiCad conversion of 04192023_DAF0TMB3IC0_F0TG_MB_C_brd_V02_OCP.brd

R3716  Q_RES  0 5% CHIP  pkg 0402LF  page 252 : A = SMB_LM75_0_3V3AUX_SDA_R ; B = SMB_LM75_0_3V3AUX_SDA

JP4003  CONN3_210HP1030BR1  CONN3_210-HP1-030BR1 IO  pkg HEADER1X3XG  page 268
  \1\  = NC
  \2\  = PDB_PRSNT_R_N
  \3\  = GND

(kicad_pcb
	(version 20260206)
	(generator "pcbnew")
	(generator_version "10.0")
	(general
		(thickness 1.6)
		(legacy_teardrops no)
	)
	(paper "A4")
	(title_block
		(title "04192023_DAF0TMB3IC0_F0TG_MB_C_brd_V02_OCP.brd")
		(comment 1 "Grand Teton / footprints 3521-3522 of 8354")
	)
	(layers
		(0 "F.Cu" signal "TOP")
		(4 "In1.Cu" signal "GND")
		(6 "In2.Cu" signal "IN1")
		(8 "In3.Cu" signal "GND1")
		(10 "In4.Cu" signal "IN2")
		(12 "In5.Cu" signal "GND2")
		(14 "In6.Cu" signal "IN3")
		(16 "In7.Cu" signal "GND3")
		(18 "In8.Cu" signal "VCC")
		(20 "In9.Cu" signal "VCC1")
		(22 "In10.Cu" signal "GND4")
		(24 "In11.Cu" signal "IN4")
		(26 "In12.Cu" signal "GND5")
		(28 "In13.Cu" signal "IN5")
		(30 "In14.Cu" signal "GND6")
		(32 "In15.Cu" signal "IN6")
		(34 "In16.Cu" signal "GND7")
		(2 "B.Cu" signal "BOTTOM")
		(9 "F.Adhes" user "F.Adhesive")
		(11 "B.Adhes" user "B.Adhesive")
		(13 "F.Paste" user "Package Geometry/Pastemask Top")
		(15 "B.Paste" user "Package Geometry/Pastemask Bottom")
		(5 "F.SilkS" user "Ref Des/Silkscreen Top")
		(7 "B.SilkS" user "Ref Des/Silkscreen Bottom")
		(1 "F.Mask" user "Board Geometry/Soldermask Top")
		(3 "B.Mask" user "Board Geometry/Soldermask Bottom")
		(17 "Dwgs.User" user "User.Drawings")
		(19 "Cmts.User" user "User.Comments")
		(21 "Eco1.User" user "User.Eco1")
		(23 "Eco2.User" user "User.Eco2")
		(25 "Edge.Cuts" user "Board Geometry/Outline")
		(27 "Margin" user)
		(31 "F.CrtYd" user "Package Geometry/Place Bound Top")
		(29 "B.CrtYd" user "Package Geometry/Place Bound Bottom")
		(35 "F.Fab" user "Ref Des/Assembly Top")
		(33 "B.Fab" user "Ref Des/Assembly Bottom")
	)
	(footprint ""
		(layer "F.Cu")
		(at 274.56638 -421.883332)
		(property "Reference" "JP4003"
			(at -3.4417 8.750808 90)
			(unlocked yes)
			(layer "F.SilkS")
			(effects
				(font
					(size 0.7874 0.5842)
					(thickness 0.1524)
				)
				(justify left)
			)
		)
		(property "Value" ""
			(at 0 0 0)
			(layer "F.Fab")
			(effects
				(font
					(size 1.27 1.27)
				)
			)
		)
		(duplicate_pad_numbers_are_jumpers no)
		(fp_line
			(start -1.249934 -1.320038)
			(end 1.249934 -1.320038)
			(stroke
				(width 0.1524)
				(type default)
			)
			(layer "F.SilkS")
		)
		(fp_line
			(start -1.249934 6.400038)
			(end -1.249934 -1.320038)
			(stroke
				(width 0.1524)
				(type default)
			)
			(layer "F.SilkS")
		)
		(fp_line
			(start 1.249934 -1.320038)
			(end 1.249934 6.400038)
			(stroke
				(width 0.1524)
				(type default)
			)
			(layer "F.SilkS")
		)
		(fp_line
			(start 1.249934 6.400038)
			(end -1.249934 6.400038)
			(stroke
				(width 0.1524)
				(type default)
			)
			(layer "F.SilkS")
		)
		(fp_poly
			(pts
				(xy -2.5654 0.556514) (xy -2.5654 -0.556514) (xy -1.452372 0)
			)
			(stroke
				(width 0)
				(type default)
			)
			(fill yes)
			(layer "F.SilkS")
		)
		(fp_line
			(start -1.249934 -1.320038)
			(end 1.249934 -1.320038)
			(stroke
				(width 0.1)
				(type default)
			)
			(layer "F.Fab")
		)
		(fp_line
			(start -1.249934 6.400038)
			(end -1.249934 -1.320038)
			(stroke
				(width 0.1)
				(type default)
			)
			(layer "F.Fab")
		)
		(fp_line
			(start 1.249934 -1.320038)
			(end 1.249934 6.400038)
			(stroke
				(width 0.1)
				(type default)
			)
			(layer "F.Fab")
		)
		(fp_line
			(start 1.249934 6.400038)
			(end -1.249934 6.400038)
			(stroke
				(width 0.1)
				(type default)
			)
			(layer "F.Fab")
		)
		(fp_poly
			(pts
				(xy -2.5654 -0.556514) (xy -1.452372 0) (xy -2.5654 0.556514)
			)
			(stroke
				(width 0)
				(type default)
			)
			(fill yes)
			(layer "F.Fab")
		)
		(fp_text user "3"
			(at -2.007362 5.130292 90)
			(unlocked yes)
			(layer "F.SilkS")
			(effects
				(font
					(size 0.7874 0.5842)
					(thickness 0.1524)
				)
			)
		)
		(fp_text user "3"
			(at -1.1557 5.18287 0)
			(unlocked yes)
			(layer "B.SilkS")
			(effects
				(font
					(size 0.7874 0.5842)
					(thickness 0.1524)
				)
				(justify mirror)
			)
		)
		(fp_text user "1"
			(at -1.143 0.02667 0)
			(unlocked yes)
			(layer "B.SilkS")
			(effects
				(font
					(size 0.7874 0.5842)
					(thickness 0.1524)
				)
				(justify mirror)
			)
		)
		(fp_text user "3"
			(at -1.1557 5.18287 0)
			(unlocked yes)
			(layer "B.Fab")
			(effects
				(font
					(size 0.7874 0.5842)
					(thickness 0.1524)
				)
				(justify mirror)
			)
		)
		(fp_text user "1"
			(at -1.143 0.02667 0)
			(unlocked yes)
			(layer "B.Fab")
			(effects
				(font
					(size 0.7874 0.5842)
					(thickness 0.1524)
				)
				(justify mirror)
			)
		)
		(fp_text user "3"
			(at -1.778 5.13207 0)
			(unlocked yes)
			(layer "F.Fab")
			(effects
				(font
					(size 0.7874 0.5842)
					(thickness 0.1524)
				)
			)
		)
		(pad "1" thru_hole rect
			(at 0 0)
			(size 1.5494 1.5494)
			(drill 1.0414)
			(layers "*.Cu" "*.Mask")
			(remove_unused_layers no)
			(net "Net_10750")
			(clearance 0)
			(padstack
				(mode front_inner_back)
				(layer "Inner"
					(shape circle)
					(size 1.5494 1.5494)
					(clearance 0)
				)
				(layer "B.Cu"
					(shape rect)
					(size 1.5494 1.5494)
					(clearance 0)
				)
			)
		)
		(pad "2" thru_hole circle
			(at 0 2.54)
			(size 1.5494 1.5494)
			(drill 1.0414)
			(layers "*.Cu" "*.Mask")
			(remove_unused_layers no)
			(net "PDB_PRSNT_R_N")
			(clearance 0)
		)
		(pad "3" thru_hole circle
			(at 0 5.08)
			(size 1.5494 1.5494)
			(drill 1.0414)
			(layers "*.Cu" "*.Mask")
			(remove_unused_layers no)
			(net "GND")
			(clearance 0)
		)
	)
	(footprint ""
		(layer "F.Cu")
		(at 257.242056 -119.92737 180)
		(property "Reference" "R3716"
			(at 0 0 180)
			(layer "F.SilkS")
			(hide yes)
			(effects
				(font
					(size 1.27 1.27)
				)
			)
		)
		(property "Value" ""
			(at 0 0 180)
			(layer "F.Fab")
			(effects
				(font
					(size 1.27 1.27)
				)
			)
		)
		(duplicate_pad_numbers_are_jumpers no)
		(fp_line
			(start 0.7874 0.4064)
			(end -0.7874 0.4064)
			(stroke
				(width 0.1524)
				(type default)
			)
			(layer "F.SilkS")
		)
		(fp_line
			(start 0.7874 -0.4064)
			(end 0.7874 0.4064)
			(stroke
				(width 0.1524)
				(type default)
			)
			(layer "F.SilkS")
		)
		(fp_line
			(start -0.7874 0.4064)
			(end -0.7874 -0.4064)
			(stroke
				(width 0.1524)
				(type default)
			)
			(layer "F.SilkS")
		)
		(fp_line
			(start -0.7874 -0.4064)
			(end 0.7874 -0.4064)
			(stroke
				(width 0.1524)
				(type default)
			)
			(layer "F.SilkS")
		)
		(fp_line
			(start 0.67945 0.3048)
			(end 0.120396 0.3048)
			(stroke
				(width 0.1)
				(type default)
			)
			(layer "F.Fab")
		)
		(fp_line
			(start 0.67945 -0.3048)
			(end 0.67945 0.3048)
			(stroke
				(width 0.1)
				(type default)
			)
			(layer "F.Fab")
		)
		(fp_line
			(start 0.12065 -0.2794)
			(end 0.12065 -0.3048)
			(stroke
				(width 0.1)
				(type default)
			)
			(layer "F.Fab")
		)
		(fp_line
			(start 0.12065 -0.3048)
			(end 0.67945 -0.3048)
			(stroke
				(width 0.1)
				(type default)
			)
			(layer "F.Fab")
		)
		(fp_line
			(start 0.120396 0.3048)
			(end 0.120396 0.2794)
			(stroke
				(width 0.1)
				(type default)
			)
			(layer "F.Fab")
		)
		(fp_line
			(start 0.120396 0.2794)
			(end -0.12065 0.2794)
			(stroke
				(width 0.1)
				(type default)
			)
			(layer "F.Fab")
		)
		(fp_line
			(start -0.12065 0.3048)
			(end -0.67945 0.3048)
			(stroke
				(width 0.1)
				(type default)
			)
			(layer "F.Fab")
		)
		(fp_line
			(start -0.12065 0.2794)
			(end -0.12065 0.3048)
			(stroke
				(width 0.1)
				(type default)
			)
			(layer "F.Fab")
		)
		(fp_line
			(start -0.12065 -0.2794)
			(end 0.12065 -0.2794)
			(stroke
				(width 0.1)
				(type default)
			)
			(layer "F.Fab")
		)
		(fp_line
			(start -0.12065 -0.305054)
			(end -0.12065 -0.2794)
			(stroke
				(width 0.1)
				(type default)
			)
			(layer "F.Fab")
		)
		(fp_line
			(start -0.67945 0.3048)
			(end -0.67945 -0.305054)
			(stroke
				(width 0.1)
				(type default)
			)
			(layer "F.Fab")
		)
		(fp_line
			(start -0.67945 -0.305054)
			(end -0.12065 -0.305054)
			(stroke
				(width 0.1)
				(type default)
			)
			(layer "F.Fab")
		)
		(pad "1" smd circle
			(at -0.40005 0 180)
			(size 0 0)
			(layers "F.Cu" "F.Mask" "F.Paste")
			(net "SMB_LM75_0_3V3AUX_SDA_R")
		)
		(pad "2" smd circle
			(at 0.40005 0 180)
			(size 0 0)
			(layers "F.Cu" "F.Mask" "F.Paste")
			(net "SMB_LM75_0_3V3AUX_SDA")
		)
	)
)
